(kicad_pcb
	(version 20260206)
	(generator "pcbnew")
	(generator_version "10.0")
	(general
		(thickness 1.6)
		(legacy_teardrops no)
	)
	(paper "A4")
	(title_block
		(title "Bryce Canyon_R.DPB_16317-1_OCP.brd")
		(comment 1 "Bryce Canyon / footprints 331-336 of 2099")
	)
	(layers
		(0 "F.Cu" signal "TOP")
		(4 "In1.Cu" signal "L2GND")
		(6 "In2.Cu" signal "L3")
		(8 "In3.Cu" signal "L4VCC")
		(10 "In4.Cu" signal "L5VCC")
		(12 "In5.Cu" signal "L6")
		(14 "In6.Cu" signal "L7GND")
		(2 "B.Cu" signal "BOTTOM")
		(9 "F.Adhes" user "F.Adhesive")
		(11 "B.Adhes" user "B.Adhesive")
		(13 "F.Paste" user "Package Geometry/Pastemask Top")
		(15 "B.Paste" user "Package Geometry/Pastemask Bottom")
		(5 "F.SilkS" user "Ref Des/Silkscreen Top")
		(7 "B.SilkS" user "Ref Des/Silkscreen Bottom")
		(1 "F.Mask" user "Board Geometry/Soldermask Top")
		(3 "B.Mask" user "Board Geometry/Soldermask Bottom")
		(17 "Dwgs.User" user "User.Drawings")
		(19 "Cmts.User" user "User.Comments")
		(21 "Eco1.User" user "User.Eco1")
		(23 "Eco2.User" user "User.Eco2")
		(25 "Edge.Cuts" user "Board Geometry/Outline")
		(27 "Margin" user)
		(31 "F.CrtYd" user "Package Geometry/Place Bound Top")
		(29 "B.CrtYd" user "Package Geometry/Place Bound Bottom")
		(35 "F.Fab" user "Ref Des/Assembly Top")
		(33 "B.Fab" user "Ref Des/Assembly Bottom")
	)
	(footprint ""
		(layer "F.Cu")
		(at 323.545962 -99.717098 180)
		(property "Reference" "Q237"
			(at 0 0 180)
			(layer "F.SilkS")
			(hide yes)
			(effects
				(font
					(size 1.27 1.27)
				)
			)
		)
		(property "Value" "2N7002K-2-GP"
			(at 0.127 -8.9662 180)
			(unlocked yes)
			(layer "F.Fab")
			(hide yes)
			(effects
				(font
					(size 1.016 1.016)
					(thickness 0.1524)
				)
			)
		)
		(property "Device Type" "SOT23DGS2D4H44"
			(at 0.127 -10.4902 180)
			(unlocked yes)
			(layer "F.Fab")
			(hide yes)
			(effects
				(font
					(size 1.016 1.016)
					(thickness 0.1524)
				)
			)
		)
		(duplicate_pad_numbers_are_jumpers no)
		(fp_line
			(start 1.651 1.778)
			(end 1.651 -1.778)
			(stroke
				(width 0.1524)
				(type default)
			)
			(layer "F.SilkS")
		)
		(fp_line
			(start 1.651 -1.778)
			(end -1.651 -1.778)
			(stroke
				(width 0.1524)
				(type default)
			)
			(layer "F.SilkS")
		)
		(fp_line
			(start -1.651 1.778)
			(end 1.651 1.778)
			(stroke
				(width 0.1524)
				(type default)
			)
			(layer "F.SilkS")
		)
		(fp_line
			(start -1.651 -1.778)
			(end -1.651 1.778)
			(stroke
				(width 0.1524)
				(type default)
			)
			(layer "F.SilkS")
		)
		(fp_poly
			(pts
				(xy -1.778 1.8796) (xy -1.778 -1.8796) (xy 1.778 -1.8796) (xy 1.778 1.8796)
			)
			(stroke
				(width 0)
				(type default)
			)
			(fill no)
			(layer "F.CrtYd")
		)
		(fp_poly
			(pts
				(xy -1.778 1.8796) (xy -1.778 -1.8796) (xy 1.778 -1.8796) (xy 1.778 1.8796)
			)
			(stroke
				(width 0)
				(type default)
			)
			(fill no)
			(layer "F.Fab")
		)
		(pad "D" smd custom
			(at 0 -0.9525 180)
			(size 0.1905 0.1905)
			(layers "F.Cu" "F.Mask" "F.Paste")
			(net "FLT_HDD18_N")
			(options
				(clearance outline)
				(anchor circle)
			)
			(primitives
				(gr_poly
					(pts
						(arc
							(start -0.1778 0.5715)
							(mid -0.321484 0.511984)
							(end -0.381 0.3683)
						)
						(arc
							(start -0.381 -0.3683)
							(mid -0.321484 -0.511984)
							(end -0.1778 -0.5715)
						)
						(arc
							(start 0.1778 -0.5715)
							(mid 0.321484 -0.511984)
							(end 0.381 -0.3683)
						)
						(arc
							(start 0.381 0.3683)
							(mid 0.321484 0.511984)
							(end 0.1778 0.5715)
						)
					)
					(width 0)
					(fill yes)
				)
			)
		)
		(pad "G" smd custom
			(at -0.98425 0.9525 180)
			(size 0.1905 0.1905)
			(layers "F.Cu" "F.Mask" "F.Paste")
			(net "DRIVE_B_18_FLT_LED")
			(options
				(clearance outline)
				(anchor circle)
			)
			(primitives
				(gr_poly
					(pts
						(arc
							(start -0.1778 0.5715)
							(mid -0.321484 0.511984)
							(end -0.381 0.3683)
						)
						(arc
							(start -0.381 -0.3683)
							(mid -0.321484 -0.511984)
							(end -0.1778 -0.5715)
						)
						(arc
							(start 0.1778 -0.5715)
							(mid 0.321484 -0.511984)
							(end 0.381 -0.3683)
						)
						(arc
							(start 0.381 0.3683)
							(mid 0.321484 0.511984)
							(end 0.1778 0.5715)
						)
					)
					(width 0)
					(fill yes)
				)
			)
		)
		(pad "S" smd custom
			(at 0.98425 0.9525 180)
			(size 0.1905 0.1905)
			(layers "F.Cu" "F.Mask" "F.Paste")
			(net "GND")
			(options
				(clearance outline)
				(anchor circle)
			)
			(primitives
				(gr_poly
					(pts
						(arc
							(start -0.1778 0.5715)
							(mid -0.321484 0.511984)
							(end -0.381 0.3683)
						)
						(arc
							(start -0.381 -0.3683)
							(mid -0.321484 -0.511984)
							(end -0.1778 -0.5715)
						)
						(arc
							(start 0.1778 -0.5715)
							(mid 0.321484 -0.511984)
							(end 0.381 -0.3683)
						)
						(arc
							(start 0.381 0.3683)
							(mid 0.321484 0.511984)
							(end 0.1778 0.5715)
						)
					)
					(width 0)
					(fill yes)
				)
			)
		)
	)
	(footprint ""
		(layer "F.Cu")
		(at 210.93938 -247.88622 180)
		(property "Reference" "R37"
			(at 0 0 180)
			(layer "F.SilkS")
			(hide yes)
			(effects
				(font
					(size 1.27 1.27)
				)
			)
		)
		(property "Value" "4K7R2F-GP"
			(at 0.064008 -3.993896 180)
			(unlocked yes)
			(layer "F.Fab")
			(hide yes)
			(effects
				(font
					(size 1.016 1.016)
					(thickness 0.1524)
				)
			)
		)
		(property "Device Type" "R402H16"
			(at 0.064008 -5.517896 180)
			(unlocked yes)
			(layer "F.Fab")
			(hide yes)
			(effects
				(font
					(size 1.016 1.016)
					(thickness 0.1524)
				)
			)
		)
		(duplicate_pad_numbers_are_jumpers no)
		(fp_line
			(start 0.508 -0.9398)
			(end -0.508 -0.9398)
			(stroke
				(width 0.1524)
				(type default)
			)
			(layer "F.SilkS")
		)
		(fp_line
			(start -0.508 -0.9398)
			(end -0.508 0.9398)
			(stroke
				(width 0.1524)
				(type default)
			)
			(layer "F.SilkS")
		)
		(fp_rect
			(start -0.508 0.9398)
			(end 0.508 -0.9398)
			(stroke
				(width 0)
				(type default)
			)
			(fill no)
			(layer "F.CrtYd")
		)
		(fp_rect
			(start -0.508 0.9398)
			(end 0.508 -0.9398)
			(stroke
				(width 0)
				(type default)
			)
			(fill no)
			(layer "F.Fab")
		)
		(pad "1" smd custom
			(at 0 -0.4445 180)
			(size 0.1397 0.1397)
			(layers "F.Cu" "F.Mask" "F.Paste")
			(net "IO_EXP4_A1")
			(options
				(clearance outline)
				(anchor circle)
			)
			(primitives
				(gr_poly
					(pts
						(arc
							(start -0.1778 -0.2794)
							(mid -0.249642 -0.249642)
							(end -0.2794 -0.1778)
						)
						(arc
							(start -0.2794 0.1778)
							(mid -0.249642 0.249642)
							(end -0.1778 0.2794)
						)
						(arc
							(start 0.1778 0.2794)
							(mid 0.249642 0.249642)
							(end 0.2794 0.1778)
						)
						(arc
							(start 0.2794 -0.1778)
							(mid 0.249642 -0.249642)
							(end 0.1778 -0.2794)
						)
					)
					(width 0)
					(fill yes)
				)
			)
		)
		(pad "2" smd custom
			(at 0 0.4445 180)
			(size 0.1397 0.1397)
			(layers "F.Cu" "F.Mask" "F.Paste")
			(net "GND")
			(options
				(clearance outline)
				(anchor circle)
			)
			(primitives
				(gr_poly
					(pts
						(arc
							(start -0.1778 -0.2794)
							(mid -0.249642 -0.249642)
							(end -0.2794 -0.1778)
						)
						(arc
							(start -0.2794 0.1778)
							(mid -0.249642 0.249642)
							(end -0.1778 0.2794)
						)
						(arc
							(start 0.1778 0.2794)
							(mid 0.249642 0.249642)
							(end 0.2794 0.1778)
						)
						(arc
							(start 0.2794 -0.1778)
							(mid 0.249642 -0.249642)
							(end 0.1778 -0.2794)
						)
					)
					(width 0)
					(fill yes)
				)
			)
		)
	)
	(footprint ""
		(layer "F.Cu")
		(at 160.485582 -129.99085 90)
		(property "Reference" "VIA33"
			(at 0 0 90)
			(layer "F.SilkS")
			(hide yes)
			(effects
				(font
					(size 1.27 1.27)
				)
			)
		)
		(property "Value" "100OHM-8L-2D36MM-L18-GP"
			(at 3.8989 0.5715 90)
			(unlocked yes)
			(layer "F.Fab")
			(hide yes)
			(effects
				(font
					(size 1.016 1.016)
					(thickness 0.1524)
				)
			)
		)
		(property "Device Type" "VIA-PCIE-4P-414097"
			(at 3.8989 -0.9525 90)
			(unlocked yes)
			(layer "F.Fab")
			(hide yes)
			(effects
				(font
					(size 1.016 1.016)
					(thickness 0.1524)
				)
			)
		)
		(duplicate_pad_numbers_are_jumpers no)
		(fp_rect
			(start -2.0701 0.4826)
			(end 2.0701 -0.4826)
			(stroke
				(width 0)
				(type default)
			)
			(fill no)
			(layer "F.CrtYd")
		)
		(fp_rect
			(start -2.0701 0.4826)
			(end 2.0701 -0.4826)
			(stroke
				(width 0)
				(type default)
			)
			(fill no)
			(layer "F.Fab")
		)
		(pad "1" thru_hole circle
			(at -1.5875 0 90)
			(size 0.508 0.508)
			(drill 0.254)
			(layers "*.Cu" "*.Mask")
			(remove_unused_layers no)
			(net "GND")
			(clearance 0.2286)
			(thermal_gap 0.2286)
		)
		(pad "2" thru_hole circle
			(at -0.5715 0 90)
			(size 0.508 0.508)
			(drill 0.254)
			(layers "*.Cu" "*.Mask")
			(remove_unused_layers no)
			(net "PHY_SCC_B_TO_DRV_B_16_DP")
			(clearance 0.2286)
			(thermal_gap 0.2286)
		)
		(pad "3" thru_hole circle
			(at 0.5715 0 90)
			(size 0.508 0.508)
			(drill 0.254)
			(layers "*.Cu" "*.Mask")
			(remove_unused_layers no)
			(net "PHY_SCC_B_TO_DRV_B_16_DN")
			(clearance 0.2286)
			(thermal_gap 0.2286)
		)
		(pad "4" thru_hole circle
			(at 1.5875 0 90)
			(size 0.508 0.508)
			(drill 0.254)
			(layers "*.Cu" "*.Mask")
			(remove_unused_layers no)
			(net "GND")
			(clearance 0.2286)
			(thermal_gap 0.2286)
		)
	)
	(footprint ""
		(layer "F.Cu")
		(at 375.004076 -99.756976 180)
		(property "Reference" "Q239"
			(at 0 0 180)
			(layer "F.SilkS")
			(hide yes)
			(effects
				(font
					(size 1.27 1.27)
				)
			)
		)
		(property "Value" "2N7002K-2-GP"
			(at 0.127 -8.9662 180)
			(unlocked yes)
			(layer "F.Fab")
			(hide yes)
			(effects
				(font
					(size 1.016 1.016)
					(thickness 0.1524)
				)
			)
		)
		(property "Device Type" "SOT23DGS2D4H44"
			(at 0.127 -10.4902 180)
			(unlocked yes)
			(layer "F.Fab")
			(hide yes)
			(effects
				(font
					(size 1.016 1.016)
					(thickness 0.1524)
				)
			)
		)
		(duplicate_pad_numbers_are_jumpers no)
		(fp_line
			(start 1.651 1.778)
			(end 1.651 -1.778)
			(stroke
				(width 0.1524)
				(type default)
			)
			(layer "F.SilkS")
		)
		(fp_line
			(start 1.651 -1.778)
			(end -1.651 -1.778)
			(stroke
				(width 0.1524)
				(type default)
			)
			(layer "F.SilkS")
		)
		(fp_line
			(start -1.651 1.778)
			(end 1.651 1.778)
			(stroke
				(width 0.1524)
				(type default)
			)
			(layer "F.SilkS")
		)
		(fp_line
			(start -1.651 -1.778)
			(end -1.651 1.778)
			(stroke
				(width 0.1524)
				(type default)
			)
			(layer "F.SilkS")
		)
		(fp_poly
			(pts
				(xy -1.778 1.8796) (xy -1.778 -1.8796) (xy 1.778 -1.8796) (xy 1.778 1.8796)
			)
			(stroke
				(width 0)
				(type default)
			)
			(fill no)
			(layer "F.CrtYd")
		)
		(fp_poly
			(pts
				(xy -1.778 1.8796) (xy -1.778 -1.8796) (xy 1.778 -1.8796) (xy 1.778 1.8796)
			)
			(stroke
				(width 0)
				(type default)
			)
			(fill no)
			(layer "F.Fab")
		)
		(pad "D" smd custom
			(at 0 -0.9525 180)
			(size 0.1905 0.1905)
			(layers "F.Cu" "F.Mask" "F.Paste")
			(net "FLT_HDD20_N")
			(options
				(clearance outline)
				(anchor circle)
			)
			(primitives
				(gr_poly
					(pts
						(arc
							(start -0.1778 0.5715)
							(mid -0.321484 0.511984)
							(end -0.381 0.3683)
						)
						(arc
							(start -0.381 -0.3683)
							(mid -0.321484 -0.511984)
							(end -0.1778 -0.5715)
						)
						(arc
							(start 0.1778 -0.5715)
							(mid 0.321484 -0.511984)
							(end 0.381 -0.3683)
						)
						(arc
							(start 0.381 0.3683)
							(mid 0.321484 0.511984)
							(end 0.1778 0.5715)
						)
					)
					(width 0)
					(fill yes)
				)
			)
		)
		(pad "G" smd custom
			(at -0.98425 0.9525 180)
			(size 0.1905 0.1905)
			(layers "F.Cu" "F.Mask" "F.Paste")
			(net "DRIVE_B_20_FLT_LED")
			(options
				(clearance outline)
				(anchor circle)
			)
			(primitives
				(gr_poly
					(pts
						(arc
							(start -0.1778 0.5715)
							(mid -0.321484 0.511984)
							(end -0.381 0.3683)
						)
						(arc
							(start -0.381 -0.3683)
							(mid -0.321484 -0.511984)
							(end -0.1778 -0.5715)
						)
						(arc
							(start 0.1778 -0.5715)
							(mid 0.321484 -0.511984)
							(end 0.381 -0.3683)
						)
						(arc
							(start 0.381 0.3683)
							(mid 0.321484 0.511984)
							(end 0.1778 0.5715)
						)
					)
					(width 0)
					(fill yes)
				)
			)
		)
		(pad "S" smd custom
			(at 0.98425 0.9525 180)
			(size 0.1905 0.1905)
			(layers "F.Cu" "F.Mask" "F.Paste")
			(net "GND")
			(options
				(clearance outline)
				(anchor circle)
			)
			(primitives
				(gr_poly
					(pts
						(arc
							(start -0.1778 0.5715)
							(mid -0.321484 0.511984)
							(end -0.381 0.3683)
						)
						(arc
							(start -0.381 -0.3683)
							(mid -0.321484 -0.511984)
							(end -0.1778 -0.5715)
						)
						(arc
							(start 0.1778 -0.5715)
							(mid 0.321484 -0.511984)
							(end 0.381 -0.3683)
						)
						(arc
							(start 0.381 0.3683)
							(mid 0.321484 0.511984)
							(end 0.1778 0.5715)
						)
					)
					(width 0)
					(fill yes)
				)
			)
		)
	)
	(footprint ""
		(layer "F.Cu")
		(at 394.589 -160.02 180)
		(property "Reference" "C294"
			(at 0 0 180)
			(layer "F.SilkS")
			(hide yes)
			(effects
				(font
					(size 1.27 1.27)
				)
			)
		)
		(property "Value" "SC4D7U25V5KX-1-GP"
			(at -0.0762 -6.1214 180)
			(unlocked yes)
			(layer "F.Fab")
			(hide yes)
			(effects
				(font
					(size 1.016 1.016)
					(thickness 0.1524)
				)
			)
		)
		(property "Device Type" "C805H58"
			(at -0.0762 -8.1534 180)
			(unlocked yes)
			(layer "F.Fab")
			(hide yes)
			(effects
				(font
					(size 1.016 1.016)
					(thickness 0.1524)
				)
			)
		)
		(duplicate_pad_numbers_are_jumpers no)
		(fp_line
			(start 0.635 0)
			(end -0.635 0)
			(stroke
				(width 0.508)
				(type default)
			)
			(layer "F.SilkS")
		)
		(fp_rect
			(start -0.9652 1.778)
			(end 0.9652 -1.778)
			(stroke
				(width 0)
				(type default)
			)
			(fill no)
			(layer "F.CrtYd")
		)
		(fp_poly
			(pts
				(xy -0.9652 -1.778) (xy 0.9652 -1.778) (xy 0.9652 1.778) (xy -0.9652 1.778)
			)
			(stroke
				(width 0)
				(type default)
			)
			(fill no)
			(layer "F.Fab")
		)
		(pad "1" smd rect
			(at 0 -0.9652 180)
			(size 1.397 1.143)
			(layers "F.Cu" "F.Mask" "F.Paste")
			(net "P12V_HDD20")
		)
		(pad "2" smd rect
			(at 0 0.9652 180)
			(size 1.397 1.143)
			(layers "F.Cu" "F.Mask" "F.Paste")
			(net "GND")
		)
	)
	(footprint ""
		(layer "F.Cu")
		(at 46.355 -145.796)
		(property "Reference" "Q54"
			(at 0 0 0)
			(layer "F.SilkS")
			(hide yes)
			(effects
				(font
					(size 1.27 1.27)
				)
			)
		)
		(property "Value" "AO4407AL-GP"
			(at -3.707384 -1.5367 0)
			(unlocked yes)
			(layer "F.Fab")
			(hide yes)
			(effects
				(font
					(size 1.016 1.016)
					(thickness 0.1524)
				)
			)
		)
		(property "Device Type" "SOIC8H69"
			(at -3.707384 -3.0607 0)
			(unlocked yes)
			(layer "F.Fab")
			(hide yes)
			(effects
				(font
					(size 1.016 1.016)
					(thickness 0.1524)
				)
			)
		)
		(duplicate_pad_numbers_are_jumpers no)
		(fp_line
			(start -2.7432 -1.4224)
			(end -2.7432 1.4224)
			(stroke
				(width 0.1524)
				(type default)
			)
			(layer "F.SilkS")
		)
		(fp_line
			(start -2.7432 1.4224)
			(end -2.6416 1.4224)
			(stroke
				(width 0.1524)
				(type default)
			)
			(layer "F.SilkS")
		)
		(fp_line
			(start -2.7432 1.4224)
			(end 2.1336 1.4224)
			(stroke
				(width 0.1524)
				(type default)
			)
			(layer "F.SilkS")
		)
		(fp_line
			(start -2.7178 -0.508)
			(end -2.1844 -0.0508)
			(stroke
				(width 0.1524)
				(type default)
			)
			(layer "F.SilkS")
		)
		(fp_line
			(start -2.6289 3.4417)
			(end -2.6289 1.4732)
			(stroke
				(width 0.381)
				(type default)
			)
			(layer "F.SilkS")
		)
		(fp_line
			(start -2.1844 -0.0508)
			(end -2.7178 0.508)
			(stroke
				(width 0.1524)
				(type default)
			)
			(layer "F.SilkS")
		)
		(fp_line
			(start 2.1336 -1.4224)
			(end -2.7432 -1.4224)
			(stroke
				(width 0.1524)
				(type default)
			)
			(layer "F.SilkS")
		)
		(fp_line
			(start 2.1336 1.4224)
			(end 2.1336 -1.4224)
			(stroke
				(width 0.1524)
				(type default)
			)
			(layer "F.SilkS")
		)
		(fp_poly
			(pts
				(xy -2.2098 -1.4224) (xy -2.2098 1.4224) (xy 2.2098 1.4224) (xy 2.2098 -1.4224)
			)
			(stroke
				(width 0)
				(type default)
			)
			(fill yes)
			(layer "F.SilkS")
		)
		(fp_rect
			(start -2.450084 2.999994)
			(end 2.450084 -2.999994)
			(stroke
				(width 0)
				(type default)
			)
			(fill no)
			(layer "F.CrtYd")
		)
		(fp_poly
			(pts
				(xy -2.8194 3.6322) (xy -2.8194 -3.6322) (xy 2.8194 -3.6322) (xy 2.8194 1.18364) (xy 2.450084 1.18364)
				(xy 2.450084 -2.999994) (xy -2.450084 -2.999994) (xy -2.450084 2.999994) (xy 2.450084 2.999994)
				(xy 2.450084 1.18618) (xy 2.8194 1.18618) (xy 2.8194 3.6322)
			)
			(stroke
				(width 0)
				(type default)
			)
			(fill no)
			(layer "F.CrtYd")
		)
		(fp_rect
			(start -2.8194 3.6322)
			(end 2.8194 -3.6322)
			(stroke
				(width 0)
				(type default)
			)
			(fill no)
			(layer "F.Fab")
		)
		(pad "1" smd rect
			(at -1.905 2.54)
			(size 0.635 1.651)
			(layers "F.Cu" "F.Mask" "F.Paste")
			(net "P12V_B")
		)
		(pad "2" smd rect
			(at -0.635 2.54)
			(size 0.635 1.651)
			(layers "F.Cu" "F.Mask" "F.Paste")
			(net "P12V_B")
		)
		(pad "3" smd rect
			(at 0.635 2.54)
			(size 0.635 1.651)
			(layers "F.Cu" "F.Mask" "F.Paste")
			(net "P12V_B")
		)
		(pad "4" smd rect
			(at 1.905 2.54)
			(size 0.635 1.651)
			(layers "F.Cu" "F.Mask" "F.Paste")
			(net "SW_HDD_N13")
		)
		(pad "5" smd rect
			(at 1.905 -2.54)
			(size 0.635 1.651)
			(layers "F.Cu" "F.Mask" "F.Paste")
			(net "P12V_HDD13")
		)
		(pad "6" smd rect
			(at 0.635 -2.54)
			(size 0.635 1.651)
			(layers "F.Cu" "F.Mask" "F.Paste")
			(net "P12V_HDD13")
		)
		(pad "7" smd rect
			(at -0.635 -2.54)
			(size 0.635 1.651)
			(layers "F.Cu" "F.Mask" "F.Paste")
			(net "P12V_HDD13")
		)
		(pad "8" smd rect
			(at -1.905 -2.54)
			(size 0.635 1.651)
			(layers "F.Cu" "F.Mask" "F.Paste")
			(net "P12V_HDD13")
		)
	)
)
